# SCM (Grand Teton) — schematic netlist excerpt (pin names and nets, part order shuffled) for the footprints in the layout excerpt that follows; sources: Cadence DE-HDL packaged netlist, KiCad conversion of 12092022_DA0F0TMDCD0_F0T_Management_Board_D_brd_V3_OCP.brd

R623  Q_RES  4.7K 1% EMPTY  pkg 0402LF  page 15 : A = P3V3_RGM ; B = RST_EXTRST_N
R564  Q_RES  0 5% EMPTY  pkg 0402LF  page 10 : A = HDD_LED_N ; B = HDD_LED_R_N

(kicad_pcb
	(version 20260206)
	(generator "pcbnew")
	(generator_version "10.0")
	(general
		(thickness 1.6)
		(legacy_teardrops no)
	)
	(paper "A4")
	(title_block
		(title "12092022_DA0F0TMDCD0_F0T_Management_Board_D_brd_V3_OCP.brd")
		(comment 1 "Grand Teton / footprints 358-359 of 1440")
	)
	(layers
		(0 "F.Cu" signal "TOP")
		(4 "In1.Cu" signal "GND")
		(6 "In2.Cu" signal "IN1")
		(8 "In3.Cu" signal "GND1")
		(10 "In4.Cu" signal "IN2")
		(12 "In5.Cu" signal "VCC")
		(14 "In6.Cu" signal "VCC1")
		(16 "In7.Cu" signal "IN3")
		(18 "In8.Cu" signal "GND2")
		(20 "In9.Cu" signal "IN4")
		(22 "In10.Cu" signal "GND3")
		(2 "B.Cu" signal "BOTTOM")
		(9 "F.Adhes" user "F.Adhesive")
		(11 "B.Adhes" user "B.Adhesive")
		(13 "F.Paste" user "Package Geometry/Pastemask Top")
		(15 "B.Paste" user "Package Geometry/Pastemask Bottom")
		(5 "F.SilkS" user "Ref Des/Silkscreen Top")
		(7 "B.SilkS" user "Ref Des/Silkscreen Bottom")
		(1 "F.Mask" user "Board Geometry/Soldermask Top")
		(3 "B.Mask" user "Board Geometry/Soldermask Bottom")
		(17 "Dwgs.User" user "User.Drawings")
		(19 "Cmts.User" user "User.Comments")
		(21 "Eco1.User" user "User.Eco1")
		(23 "Eco2.User" user "User.Eco2")
		(25 "Edge.Cuts" user "Board Geometry/Outline")
		(27 "Margin" user)
		(31 "F.CrtYd" user "Package Geometry/Place Bound Top")
		(29 "B.CrtYd" user "Package Geometry/Place Bound Bottom")
		(35 "F.Fab" user "Ref Des/Assembly Top")
		(33 "B.Fab" user "Ref Des/Assembly Bottom")
	)
	(footprint ""
		(layer "F.Cu")
		(at 59.311794 -34.688526 90)
		(property "Reference" "R623"
			(at 0 0 90)
			(layer "F.SilkS")
			(hide yes)
			(effects
				(font
					(size 1.27 1.27)
				)
			)
		)
		(property "Value" ""
			(at 0 0 90)
			(layer "F.Fab")
			(effects
				(font
					(size 1.27 1.27)
				)
			)
		)
		(duplicate_pad_numbers_are_jumpers no)
		(fp_line
			(start 0.7874 -0.4064)
			(end 0.7874 0.4064)
			(stroke
				(width 0.1524)
				(type default)
			)
			(layer "F.SilkS")
		)
		(fp_line
			(start -0.7874 -0.4064)
			(end 0.7874 -0.4064)
			(stroke
				(width 0.1524)
				(type default)
			)
			(layer "F.SilkS")
		)
		(fp_line
			(start 0.7874 0.4064)
			(end -0.7874 0.4064)
			(stroke
				(width 0.1524)
				(type default)
			)
			(layer "F.SilkS")
		)
		(fp_line
			(start -0.7874 0.4064)
			(end -0.7874 -0.4064)
			(stroke
				(width 0.1524)
				(type default)
			)
			(layer "F.SilkS")
		)
		(fp_line
			(start -0.12065 -0.305054)
			(end -0.12065 -0.2794)
			(stroke
				(width 0.1)
				(type default)
			)
			(layer "F.Fab")
		)
		(fp_line
			(start -0.67945 -0.305054)
			(end -0.12065 -0.305054)
			(stroke
				(width 0.1)
				(type default)
			)
			(layer "F.Fab")
		)
		(fp_line
			(start 0.67945 -0.3048)
			(end 0.67945 0.3048)
			(stroke
				(width 0.1)
				(type default)
			)
			(layer "F.Fab")
		)
		(fp_line
			(start 0.12065 -0.3048)
			(end 0.67945 -0.3048)
			(stroke
				(width 0.1)
				(type default)
			)
			(layer "F.Fab")
		)
		(fp_line
			(start 0.12065 -0.2794)
			(end 0.12065 -0.3048)
			(stroke
				(width 0.1)
				(type default)
			)
			(layer "F.Fab")
		)
		(fp_line
			(start -0.12065 -0.2794)
			(end 0.12065 -0.2794)
			(stroke
				(width 0.1)
				(type default)
			)
			(layer "F.Fab")
		)
		(fp_line
			(start 0.120396 0.2794)
			(end -0.12065 0.2794)
			(stroke
				(width 0.1)
				(type default)
			)
			(layer "F.Fab")
		)
		(fp_line
			(start -0.12065 0.2794)
			(end -0.12065 0.3048)
			(stroke
				(width 0.1)
				(type default)
			)
			(layer "F.Fab")
		)
		(fp_line
			(start 0.67945 0.3048)
			(end 0.120396 0.3048)
			(stroke
				(width 0.1)
				(type default)
			)
			(layer "F.Fab")
		)
		(fp_line
			(start 0.120396 0.3048)
			(end 0.120396 0.2794)
			(stroke
				(width 0.1)
				(type default)
			)
			(layer "F.Fab")
		)
		(fp_line
			(start -0.12065 0.3048)
			(end -0.67945 0.3048)
			(stroke
				(width 0.1)
				(type default)
			)
			(layer "F.Fab")
		)
		(fp_line
			(start -0.67945 0.3048)
			(end -0.67945 -0.305054)
			(stroke
				(width 0.1)
				(type default)
			)
			(layer "F.Fab")
		)
		(pad "1" smd circle
			(at -0.40005 0 90)
			(size 0 0)
			(layers "F.Cu" "F.Mask" "F.Paste")
			(net "P3V3_RGM")
		)
		(pad "2" smd circle
			(at 0.40005 0 90)
			(size 0 0)
			(layers "F.Cu" "F.Mask" "F.Paste")
			(net "RST_EXTRST_N")
		)
	)
	(footprint ""
		(layer "F.Cu")
		(at 12.3444 -109.347 90)
		(property "Reference" "R564"
			(at 0 0 90)
			(layer "F.SilkS")
			(hide yes)
			(effects
				(font
					(size 1.27 1.27)
				)
			)
		)
		(property "Value" ""
			(at 0 0 90)
			(layer "F.Fab")
			(effects
				(font
					(size 1.27 1.27)
				)
			)
		)
		(duplicate_pad_numbers_are_jumpers no)
		(fp_line
			(start 0.7874 -0.4064)
			(end 0.7874 0.4064)
			(stroke
				(width 0.1524)
				(type default)
			)
			(layer "F.SilkS")
		)
		(fp_line
			(start -0.7874 -0.4064)
			(end 0.7874 -0.4064)
			(stroke
				(width 0.1524)
				(type default)
			)
			(layer "F.SilkS")
		)
		(fp_line
			(start 0.7874 0.4064)
			(end -0.7874 0.4064)
			(stroke
				(width 0.1524)
				(type default)
			)
			(layer "F.SilkS")
		)
		(fp_line
			(start -0.7874 0.4064)
			(end -0.7874 -0.4064)
			(stroke
				(width 0.1524)
				(type default)
			)
			(layer "F.SilkS")
		)
		(fp_line
			(start -0.12065 -0.305054)
			(end -0.12065 -0.2794)
			(stroke
				(width 0.1)
				(type default)
			)
			(layer "F.Fab")
		)
		(fp_line
			(start -0.67945 -0.305054)
			(end -0.12065 -0.305054)
			(stroke
				(width 0.1)
				(type default)
			)
			(layer "F.Fab")
		)
		(fp_line
			(start 0.67945 -0.3048)
			(end 0.67945 0.3048)
			(stroke
				(width 0.1)
				(type default)
			)
			(layer "F.Fab")
		)
		(fp_line
			(start 0.12065 -0.3048)
			(end 0.67945 -0.3048)
			(stroke
				(width 0.1)
				(type default)
			)
			(layer "F.Fab")
		)
		(fp_line
			(start 0.12065 -0.2794)
			(end 0.12065 -0.3048)
			(stroke
				(width 0.1)
				(type default)
			)
			(layer "F.Fab")
		)
		(fp_line
			(start -0.12065 -0.2794)
			(end 0.12065 -0.2794)
			(stroke
				(width 0.1)
				(type default)
			)
			(layer "F.Fab")
		)
		(fp_line
			(start 0.120396 0.2794)
			(end -0.12065 0.2794)
			(stroke
				(width 0.1)
				(type default)
			)
			(layer "F.Fab")
		)
		(fp_line
			(start -0.12065 0.2794)
			(end -0.12065 0.3048)
			(stroke
				(width 0.1)
				(type default)
			)
			(layer "F.Fab")
		)
		(fp_line
			(start 0.67945 0.3048)
			(end 0.120396 0.3048)
			(stroke
				(width 0.1)
				(type default)
			)
			(layer "F.Fab")
		)
		(fp_line
			(start 0.120396 0.3048)
			(end 0.120396 0.2794)
			(stroke
				(width 0.1)
				(type default)
			)
			(layer "F.Fab")
		)
		(fp_line
			(start -0.12065 0.3048)
			(end -0.67945 0.3048)
			(stroke
				(width 0.1)
				(type default)
			)
			(layer "F.Fab")
		)
		(fp_line
			(start -0.67945 0.3048)
			(end -0.67945 -0.305054)
			(stroke
				(width 0.1)
				(type default)
			)
			(layer "F.Fab")
		)
		(pad "1" smd circle
			(at -0.40005 0 90)
			(size 0 0)
			(layers "F.Cu" "F.Mask" "F.Paste")
			(net "HDD_LED_N")
		)
		(pad "2" smd circle
			(at 0.40005 0 90)
			(size 0 0)
			(layers "F.Cu" "F.Mask" "F.Paste")
			(net "HDD_LED_R_N")
		)
	)
)
